FILE_TYPE = CONNECTIVITY;
{Allegro Design Entry HDL 17.4-2019 S026 (4007227) 1/17/2022}
"PAGE_NUMBER" = 301;
0"NC";
1"AGND_HSC\g";
2"HSC_VDD\g";
3"AGND_HSC\g";
4"AGND_HSC\g";
5"AGND_HSC\g";
6"HSC_VDD\g";
7"HSC_CS_2";
8"HSC_IMON";
9"AGND_HSC\g";
10"P12V_AUX\g";
11"HSC_SS";
12"HSC_VTEMP";
13"HSC_FAULT";
14"HSC_MODE_2";
15"AGND_HSC\g";
16"HSC_OCREF";
17"HSC_ON";
18"HSC_VDD_R_1";
19"HSC_SCREF_1";
20"HSC_MODE_1";
21"HSC_SS";
22"HSC_VTEMP";
23"HSC_FAULT";
24"HSC_D_OC_2";
25"AGND_HSC\g";
26"P12V_AUX\g";
27"P12V_PSU\g";
28"AGND_HSC\g";
29"P12V_PSU\g";
30"HSC_FLT_TYPE";
31"HSC_FLT_TYPE_2";
32"HSC_VDD_R_2";
33"HSC_OCREF";
34"HSC_ON";
35"HSC_SCREF_2";
36"HSC_SCREF";
37"HSC_FLT_TYPE";
38"HSC_D_OC_1";
39"HSC_D_OC_R";
40"HSC_NC1_1";
41"HSC_FLT_TYPE_1";
42"HSC_CS_1";
43"HSC_IMON";
44"HSC_SCREF";
45"HSC_D_OC_R";
46"HSC_NC1_2";
%"UNIVERSAL_GND"
"1","(-2650,-2400)","0","pure_quanta_power","I1";
;
HDL_POWER"AGND_HSC"
CDS_LIB"pure_quanta_power";
"A"9;
%"Q_RES"
"1","(-1925,-1250)","0","pure_quanta","I11";
;
LOCATION"PR3912"
$SEC"1"
CDS_SEC"1"
ROOM"HSC BOM1"
VALUE"120K"
MATERIAL"CHIP"
PACK_TYPE"0402LF"
WATTAGE"1/16W"
TOLERANCE"1%"
CDS_LIB"pure_quanta"
PART_NUMBER"CS41202FB05";
"B"
$PN"2"14;
"A"
$PN"1"25;
%"Q_CAP"
"1","(-1975,-2075)","0","pure_quanta","I12";
;
LOCATION"PC2348"
$SEC"1"
CDS_SEC"1"
MATERIAL"EMPTY"
VALUE"1NF"
PACK_TYPE"0402"
ROOM"HSC BOM1"
VOLTAGE"50V"
TOLERANCE"10%"
CDS_LIB"pure_quanta"
PART_NUMBER"CH21006KB16";
"B"
$PN"2"9;
"A"
$PN"1"33;
%"Q_RES"
"2","(-1500,-2075)","0","pure_quanta","I13";
;
LOCATION"PR3915"
$SEC"1"
CDS_SEC"1"
VALUE"2K"
TOLERANCE"0.1%"
PACK_TYPE"0402LF"
ROOM"HSC BOM1"
MATERIAL"CHIP"
WATTAGE"1/16W"
CDS_LIB"pure_quanta"
PART_NUMBER"CS22002BB07";
"A"
$PN"1"7;
"B"
$PN"2"9;
%"Q_RES"
"2","(-975,-2075)","0","pure_quanta","I15";
;
LOCATION"PR1101"
$SEC"1"
CDS_SEC"1"
TOLERANCE"0.1%"
VALUE"2K"
ROOM"HSC BOM1"
PACK_TYPE"0402LF"
MATERIAL"CHIP"
WATTAGE"1/16W"
CDS_LIB"pure_quanta"
PART_NUMBER"CS22002BB07";
"A"
$PN"1"8;
"B"
$PN"2"9;
%"MP5991GLUZ"
"1","(0,-1325)","0","pure_quanta","I16";
;
LOCATION"PU288"
SEC"1"
MATERIAL"IC"
PART_TYPE"SMLF"
ROOM"HSC BOM1"
VALUE"MP5991GLU-Z"
NEEDS_NO_SIZE"TRUE"
CDS_LMAN_SYM_OUTLINE"-325,775,325,-775"
CDS_LIB"pure_quanta"
SEC_TYPE""
PART_NUMBER"AL005991A00";
"NC1"
$PN"7"46;
"FLT_TYPE"
$PN"6"31;
"SCREF_OCWREF"
$PN"17"35;
"MODE"
$PN"8"14;
"VOUT10"
$PN"32"10;
"VOUT9"
$PN"31"10;
"VOUT8"
$PN"30"10;
"VOUT7"
$PN"29"10;
"VOUT6"
$PN"28"10;
"VOUT5"
$PN"27"10;
"VIN9"
$PN"33"29;
"VIN8"
$PN"16"29;
"VIN7"
$PN"15"29;
"VIN6"
$PN"14"29;
"D_OC"
$PN"3"24;
"VOUT4"
$PN"26"10;
"VOUT3"
$PN"25"10;
"VOUT2"
$PN"2"10;
"VOUT1"
$PN"1"10;
"VTEMP"
$PN"18"22;
"GOK"
$PN"5"23;
"SS"
$PN"19"21;
"GND"
$PN"20"9;
"VDD33"
$PN"21"32;
"IMON"
$PN"22"8;
"CS"
$PN"23"7;
"OCREF"
$PN"24"33;
"ON"
$PN"4"34;
"VIN5"
$PN"13"29;
"VIN4"
$PN"12"29;
"VIN3"
$PN"11"29;
"VIN2"
$PN"10"29;
"VIN1"
$PN"9"29;
%"Q_RES"
"1","(-1325,-1425)","0","pure_quanta","I17";
;
LOCATION"PR3917"
$SEC"1"
CDS_SEC"1"
WATTAGE"1/16W"
PACK_TYPE"0402LF"
VALUE"0"
TOLERANCE"5%"
MATERIAL"CHIP"
ROOM"HSC BOM1"
CDS_LIB"pure_quanta"
PART_NUMBER"CS00002JB13";
"B"
$PN"2"35;
"A"
$PN"1"36;
%"UNIVERSAL_POWER"
"1","(-975,-450)","0","pure_quanta_power","I18";
;
HDL_POWER"P12V_PSU"
BOM_COST"MIO_VRD_SB"
CDS_LIB"pure_quanta_power";
"A"29;
%"UNIVERSAL_GND"
"1","(-3450,1075)","0","pure_quanta_power","I19";
;
HDL_POWER"AGND_HSC"
CDS_LIB"pure_quanta_power";
"A"1;
%"Q_CAP"
"1","(-2650,-2075)","0","pure_quanta","I2";
;
LOCATION"PC2183"
$SEC"1"
CDS_SEC"1"
VALUE"220PF"
VOLTAGE"50V"
PACK_TYPE"0402"
MATERIAL"EMPTY"
ROOM"HSC BOM1"
CDS_LIB"pure_quanta"
TOLERANCE"10%"
PART_NUMBER"TMP_QCH12206KB14";
"B"
$PN"2"9;
"A"
$PN"1"34;
%"Q_CAP"
"1","(-3450,1375)","0","pure_quanta","I20";
;
LOCATION"PC1525"
$SEC"1"
CDS_SEC"1"
MATERIAL"X6S"
VOLTAGE"25V"
PACK_TYPE"C0402"
VALUE"1UF"
ROOM"HSC BOM1"
CDS_LIB"pure_quanta"
TOLERANCE"10%"
PART_NUMBER"CH5104KEB02";
"B"
$PN"2"1;
"A"
$PN"1"18;
%"Q_RES"
"1","(-3450,1850)","1","pure_quanta","I21";
;
LOCATION"PR3910"
$SEC"1"
CDS_SEC"1"
WATTAGE"1/16W"
MATERIAL"CHIP"
TOLERANCE"5%"
VALUE"0"
PACK_TYPE"0402LF"
ROOM"HSC BOM1"
CDS_LIB"pure_quanta"
PART_NUMBER"CS00002JB13";
"B"
$PN"2"2;
"A"
$PN"1"18;
%"UNIVERSAL_POWER"
"1","(-3450,2100)","0","pure_quanta_power","I22";
;
HDL_POWER"HSC_VDD"
CDS_LIB"pure_quanta_power"
BOM_COST"MIO_VRD_SB";
"A"2;
%"UNIVERSAL_GND"
"1","(-2675,425)","0","pure_quanta_power","I23";
;
HDL_POWER"AGND_HSC"
CDS_LIB"pure_quanta_power";
"A"15;
%"Q_CAP"
"1","(-2675,725)","0","pure_quanta","I24";
;
LOCATION"PC2182"
$SEC"1"
CDS_SEC"1"
VALUE"220PF"
VOLTAGE"50V"
MATERIAL"X7R"
PACK_TYPE"0402"
ROOM"HSC BOM1"
TOLERANCE"10%"
CDS_LIB"pure_quanta"
PART_NUMBER"TMP_QCH12206KB14";
"B"
$PN"2"15;
"A"
$PN"1"17;
%"UNIVERSAL_GND"
"1","(-2625,1475)","0","pure_quanta_power","I27";
;
HDL_POWER"AGND_HSC"
CDS_LIB"pure_quanta_power";
"A"28;
%"Q_RES"
"1","(-1925,1550)","0","pure_quanta","I29";
;
LOCATION"PR1134"
$SEC"1"
CDS_SEC"1"
MATERIAL"CHIP"
VALUE"120K"
PACK_TYPE"0402LF"
TOLERANCE"1%"
ROOM"HSC BOM1"
WATTAGE"1/16W"
CDS_LIB"pure_quanta"
PART_NUMBER"CS41202FB05";
"B"
$PN"2"20;
"A"
$PN"1"28;
%"UNIVERSAL_GND"
"1","(-3475,-1725)","0","pure_quanta_power","I3";
;
HDL_POWER"AGND_HSC"
CDS_LIB"pure_quanta_power";
"A"3;
%"Q_CAP"
"1","(-2000,725)","0","pure_quanta","I30";
;
LOCATION"PC2347"
$SEC"1"
CDS_SEC"1"
PACK_TYPE"0402"
VALUE"1NF"
VOLTAGE"50V"
MATERIAL"EMPTY"
ROOM"HSC BOM1"
TOLERANCE"10%"
CDS_LIB"pure_quanta"
PART_NUMBER"CH21006KB16";
"B"
$PN"2"15;
"A"
$PN"1"16;
%"Q_RES"
"2","(-1500,725)","0","pure_quanta","I31";
;
LOCATION"PR3914"
$SEC"1"
CDS_SEC"1"
MATERIAL"CHIP"
WATTAGE"1/16W"
TOLERANCE"0.1%"
VALUE"2K"
PACK_TYPE"0402LF"
ROOM"HSC BOM1"
CDS_LIB"pure_quanta"
PART_NUMBER"CS22002BB07";
"A"
$PN"1"42;
"B"
$PN"2"15;
%"Q_RES"
"1","(-1350,1375)","0","pure_quanta","I33";
;
LOCATION"PR3916"
$SEC"1"
CDS_SEC"1"
PACK_TYPE"0402LF"
WATTAGE"1/16W"
VALUE"0"
ROOM"HSC BOM1"
MATERIAL"CHIP"
TOLERANCE"5%"
CDS_LIB"pure_quanta"
PART_NUMBER"CS00002JB13";
"B"
$PN"2"19;
"A"
$PN"1"44;
%"Q_RES"
"2","(-975,725)","0","pure_quanta","I34";
;
LOCATION"PR3918"
$SEC"1"
CDS_SEC"1"
ROOM"HSC BOM1"
MATERIAL"CHIP"
WATTAGE"1/16W"
TOLERANCE"0.1%"
VALUE"2K"
PACK_TYPE"0402LF"
CDS_LIB"pure_quanta"
PART_NUMBER"CS22002BB07";
"A"
$PN"1"43;
"B"
$PN"2"15;
%"MP5991GLUZ"
"1","(0,1475)","0","pure_quanta","I35";
;
LOCATION"PU287"
SEC"1"
MATERIAL"IC"
ROOM"HSC BOM1"
PART_TYPE"SMLF"
VALUE"MP5991GLU-Z"
CDS_LIB"pure_quanta"
CDS_LMAN_SYM_OUTLINE"-325,775,325,-775"
NEEDS_NO_SIZE"TRUE"
SEC_TYPE""
PART_NUMBER"AL005991A00";
"NC1"
$PN"7"40;
"FLT_TYPE"
$PN"6"41;
"SCREF_OCWREF"
$PN"17"19;
"MODE"
$PN"8"20;
"VOUT10"
$PN"32"26;
"VOUT9"
$PN"31"26;
"VOUT8"
$PN"30"26;
"VOUT7"
$PN"29"26;
"VOUT6"
$PN"28"26;
"VOUT5"
$PN"27"26;
"VIN9"
$PN"33"27;
"VIN8"
$PN"16"27;
"VIN7"
$PN"15"27;
"VIN6"
$PN"14"27;
"D_OC"
$PN"3"38;
"VOUT4"
$PN"26"26;
"VOUT3"
$PN"25"26;
"VOUT2"
$PN"2"26;
"VOUT1"
$PN"1"26;
"VTEMP"
$PN"18"12;
"GOK"
$PN"5"13;
"SS"
$PN"19"11;
"GND"
$PN"20"15;
"VDD33"
$PN"21"18;
"IMON"
$PN"22"43;
"CS"
$PN"23"42;
"OCREF"
$PN"24"16;
"ON"
$PN"4"17;
"VIN5"
$PN"13"27;
"VIN4"
$PN"12"27;
"VIN3"
$PN"11"27;
"VIN2"
$PN"10"27;
"VIN1"
$PN"9"27;
%"UNIVERSAL_POWER"
"1","(-975,2350)","0","pure_quanta_power","I36";
;
HDL_POWER"P12V_PSU"
CDS_LIB"pure_quanta_power"
BOM_COST"MIO_VRD_SB";
"A"27;
%"UNIVERSAL_GND"
"1","(975,-2275)","0","pure_quanta_power","I37";
;
HDL_POWER"AGND_HSC"
CDS_LIB"pure_quanta_power";
"A"4;
%"Q_CAP"
"1","(975,-2050)","0","pure_quanta","I38";
;
LOCATION"PC2185"
$SEC"1"
CDS_SEC"1"
MATERIAL"X7R"
PACK_TYPE"0402"
VALUE"0.068UF"
ROOM"HSC BOM1"
VOLTAGE"16V"
CDS_LIB"pure_quanta"
TOLERANCE"10%"
PART_NUMBER"CH3683K1B09";
"B"
$PN"2"4;
"A"
$PN"1"21;
%"Q_RES"
"1","(1475,-1500)","0","pure_quanta","I39";
;
LOCATION"PR3922"
$SEC"1"
CDS_SEC"1"
ROOM"HSC BOM1"
MATERIAL"CHIP"
TOLERANCE"5%"
WATTAGE"1/16W"
VALUE"0"
PACK_TYPE"0402LF"
CDS_LIB"pure_quanta"
PART_NUMBER"CS00002JB13";
"B"
$PN"2"30;
"A"
$PN"1"31;
%"Q_CAP"
"1","(-3475,-1425)","0","pure_quanta","I4";
;
LOCATION"PC2181"
$SEC"1"
CDS_SEC"1"
ROOM"HSC BOM1"
PACK_TYPE"C0402"
MATERIAL"X6S"
VOLTAGE"25V"
VALUE"1UF"
CDS_LIB"pure_quanta"
TOLERANCE"10%"
PART_NUMBER"CH5104KEB02";
"B"
$PN"2"3;
"A"
$PN"1"32;
%"Q_RES"
"1","(1475,-1325)","0","pure_quanta","I40";
;
LOCATION"PR3921"
$SEC"1"
CDS_SEC"1"
PACK_TYPE"0402LF"
TOLERANCE"5%"
MATERIAL"CHIP"
ROOM"HSC BOM1"
VALUE"0"
WATTAGE"1/16W"
CDS_LIB"pure_quanta"
PART_NUMBER"CS00002JB13";
"B"
$PN"2"45;
"A"
$PN"1"24;
%"UNIVERSAL_POWER"
"1","(1100,-450)","0","pure_quanta_power","I41";
;
HDL_POWER"P12V_AUX"
BOM_COST"MIO_VRD_SB"
CDS_LIB"pure_quanta_power";
"A"10;
%"Q_CAP"
"1","(975,750)","0","pure_quanta","I47";
;
LOCATION"PC2184"
$SEC"1"
CDS_SEC"1"
VOLTAGE"16V"
MATERIAL"X7R"
PACK_TYPE"0402"
ROOM"HSC BOM1"
VALUE"0.068UF"
CDS_LIB"pure_quanta"
TOLERANCE"10%"
PART_NUMBER"CH3683K1B09";
"B"
$PN"2"5;
"A"
$PN"1"11;
%"UNIVERSAL_GND"
"1","(975,525)","0","pure_quanta_power","I48";
;
HDL_POWER"AGND_HSC"
CDS_LIB"pure_quanta_power";
"A"5;
%"Q_RES"
"1","(1475,1300)","0","pure_quanta","I49";
;
LOCATION"PR3920"
$SEC"1"
CDS_SEC"1"
ROOM"HSC BOM1"
PACK_TYPE"0402LF"
WATTAGE"1/16W"
VALUE"0"
TOLERANCE"5%"
MATERIAL"CHIP"
CDS_LIB"pure_quanta"
PART_NUMBER"CS00002JB13";
"B"
$PN"2"37;
"A"
$PN"1"41;
%"Q_RES"
"1","(-3475,-950)","1","pure_quanta","I5";
;
LOCATION"PR3911"
$SEC"1"
CDS_SEC"1"
TOLERANCE"5%"
MATERIAL"CHIP"
VALUE"0"
PACK_TYPE"0402LF"
WATTAGE"1/16W"
ROOM"HSC BOM1"
CDS_LIB"pure_quanta"
PART_NUMBER"CS00002JB13";
"B"
$PN"2"6;
"A"
$PN"1"32;
%"Q_RES"
"1","(1475,1475)","0","pure_quanta","I50";
;
LOCATION"PR3919"
$SEC"1"
CDS_SEC"1"
PACK_TYPE"0402LF"
VALUE"0"
WATTAGE"1/16W"
ROOM"HSC BOM1"
TOLERANCE"5%"
MATERIAL"CHIP"
CDS_LIB"pure_quanta"
PART_NUMBER"CS00002JB13";
"B"
$PN"2"39;
"A"
$PN"1"38;
%"UNIVERSAL_POWER"
"1","(1100,2350)","0","pure_quanta_power","I51";
;
HDL_POWER"P12V_AUX"
CDS_LIB"pure_quanta_power"
BOM_COST"MIO_VRD_SB";
"A"26;
%"UNIVERSAL_POWER"
"1","(-3475,-700)","0","pure_quanta_power","I6";
;
HDL_POWER"HSC_VDD"
CDS_LIB"pure_quanta_power"
BOM_COST"MIO_VRD_SB";
"A"6;
%"UNIVERSAL_GND"
"1","(-2725,-1350)","0","pure_quanta_power","I8";
;
HDL_POWER"AGND_HSC"
CDS_LIB"pure_quanta_power";
"A"25;
END.
